# BASEBOARD_FAB2 (Tioga Pass) — schematic netlist excerpt (pin names and nets, part order shuffled) for the footprints in the layout excerpt that follows; sources: Cadence DE-HDL packaged netlist, KiCad conversion of Wiwynn_Tioga_Pass_MB.brd

U8F1  PI3B3257A  IC  pkg TSSOPLF  page 154
  S  = FM_BIOS_SPI_BMC_CTRL
  IA0  = SPI_PCH_CLK
  IA1  = SPI_BMC_CLK
  YA  = SPI_SWITCH_CLK
  IB0  = SPI_PCH_MOSI
  IB1  = SPI_BMC_DO
  YB  = SPI_SWITCH_MOSI
  GND  = GND
  YC  = SPI_SWITCH_CS0_N
  IC1  = SPI_BMC_CS0_N
  IC0  = SPI_PCH_CS0_N
  YD  = SPI_SWITCH_MISO
  ID1  = SPI_BMC_DI
  ID0  = SPI_PCH_MISO_R
  EN  = GND
  VCC  = P3V3_STBY

C8W4  CAP  100UF 4V 20% X5R  pkg 0805  page 76 : A = PVCCIN_CPU1 ; B = GND

(kicad_pcb
	(version 20260206)
	(generator "pcbnew")
	(generator_version "10.0")
	(general
		(thickness 1.6)
		(legacy_teardrops no)
	)
	(paper "A4")
	(title_block
		(title "Wiwynn_Tioga_Pass_MB.brd")
		(comment 1 "Tioga Pass / footprints 3795-3796 of 4770")
	)
	(layers
		(0 "F.Cu" signal "TOP")
		(4 "In1.Cu" signal "L2GND")
		(6 "In2.Cu" signal "L3")
		(8 "In3.Cu" signal "L4GND")
		(10 "In4.Cu" signal "L5")
		(12 "In5.Cu" signal "L6GND")
		(14 "In6.Cu" signal "L7VCC")
		(16 "In7.Cu" signal "L8VCC")
		(18 "In8.Cu" signal "L9GND")
		(20 "In9.Cu" signal "L10")
		(22 "In10.Cu" signal "L11GND")
		(24 "In11.Cu" signal "L12")
		(26 "In12.Cu" signal "L13GND")
		(2 "B.Cu" signal "BOTTOM")
		(9 "F.Adhes" user "F.Adhesive")
		(11 "B.Adhes" user "B.Adhesive")
		(13 "F.Paste" user "Package Geometry/Pastemask Top")
		(15 "B.Paste" user "Package Geometry/Pastemask Bottom")
		(5 "F.SilkS" user "Ref Des/Silkscreen Top")
		(7 "B.SilkS" user "Ref Des/Silkscreen Bottom")
		(1 "F.Mask" user "Board Geometry/Soldermask Top")
		(3 "B.Mask" user "Board Geometry/Soldermask Bottom")
		(17 "Dwgs.User" user "User.Drawings")
		(19 "Cmts.User" user "User.Comments")
		(21 "Eco1.User" user "User.Eco1")
		(23 "Eco2.User" user "User.Eco2")
		(25 "Edge.Cuts" user "Board Geometry/Outline")
		(27 "Margin" user)
		(31 "F.CrtYd" user "Package Geometry/Place Bound Top")
		(29 "B.CrtYd" user "Package Geometry/Place Bound Bottom")
		(35 "F.Fab" user "Ref Des/Assembly Top")
		(33 "B.Fab" user "Ref Des/Assembly Bottom")
	)
	(footprint ""
		(layer "B.Cu")
		(at 382.5875 -54.8005)
		(property "Reference" "U8F1"
			(at -1.43002 5.67563 0)
			(unlocked yes)
			(layer "B.SilkS")
			(effects
				(font
					(size 0.7874 0.5842)
					(thickness 0.1524)
				)
				(justify left mirror)
			)
		)
		(property "Value" ""
			(at 0 0 0)
			(layer "B.Fab")
			(effects
				(font
					(size 1.27 1.27)
				)
				(justify mirror)
			)
		)
		(duplicate_pad_numbers_are_jumpers no)
		(fp_line
			(start -3.9243 -0.2794)
			(end -3.9243 4.7244)
			(stroke
				(width 0.1524)
				(type default)
			)
			(layer "B.SilkS")
		)
		(fp_line
			(start -3.9243 4.7244)
			(end -1.5367 4.7244)
			(stroke
				(width 0.1524)
				(type default)
			)
			(layer "B.SilkS")
		)
		(fp_line
			(start -3.1242 -0.2794)
			(end -3.1242 0.7366)
			(stroke
				(width 0.1524)
				(type default)
			)
			(layer "B.SilkS")
		)
		(fp_line
			(start -3.1242 0.7366)
			(end -2.3622 0.7366)
			(stroke
				(width 0.1524)
				(type default)
			)
			(layer "B.SilkS")
		)
		(fp_line
			(start -2.3622 -0.2794)
			(end -3.1242 -0.2794)
			(stroke
				(width 0.1524)
				(type default)
			)
			(layer "B.SilkS")
		)
		(fp_line
			(start -2.3622 0.7366)
			(end -2.3622 -0.2794)
			(stroke
				(width 0.1524)
				(type default)
			)
			(layer "B.SilkS")
		)
		(fp_line
			(start -1.5367 -0.2794)
			(end -3.9243 -0.2794)
			(stroke
				(width 0.1524)
				(type default)
			)
			(layer "B.SilkS")
		)
		(fp_line
			(start -1.5367 4.7244)
			(end -1.5367 -0.2794)
			(stroke
				(width 0.1524)
				(type default)
			)
			(layer "B.SilkS")
		)
		(fp_circle
			(center 1.5494 -0.6604)
			(end 1.7399 -0.6604)
			(stroke
				(width 0.381)
				(type default)
			)
			(fill no)
			(layer "B.SilkS")
		)
		(fp_poly
			(pts
				(xy -0.7366 -0.2794) (xy -4.7244 -0.2794) (xy -4.7244 4.7244) (xy -0.7366 4.7244)
			)
			(stroke
				(width 0)
				(type default)
			)
			(fill no)
			(layer "B.CrtYd")
		)
		(fp_line
			(start -4.7244 -0.2794)
			(end -4.7244 4.7244)
			(stroke
				(width 0.1)
				(type default)
			)
			(layer "B.Fab")
		)
		(fp_line
			(start -4.7244 4.7244)
			(end -0.7366 4.7244)
			(stroke
				(width 0.1)
				(type default)
			)
			(layer "B.Fab")
		)
		(fp_line
			(start -0.7366 -0.2794)
			(end -4.7244 -0.2794)
			(stroke
				(width 0.1)
				(type default)
			)
			(layer "B.Fab")
		)
		(fp_line
			(start -0.7366 4.7244)
			(end -0.7366 -0.2794)
			(stroke
				(width 0.1)
				(type default)
			)
			(layer "B.Fab")
		)
		(fp_circle
			(center 1.5494 -0.6604)
			(end 1.7399 -0.6604)
			(stroke
				(width 0.381)
				(type default)
			)
			(fill no)
			(layer "B.Fab")
		)
		(pad "1" smd rect
			(at 0 0 180)
			(size 2.159 0.381)
			(layers "B.Cu" "B.Mask" "B.Paste")
			(net "FM_BIOS_SPI_BMC_CTRL")
		)
		(pad "2" smd rect
			(at 0 0.635 180)
			(size 2.159 0.381)
			(layers "B.Cu" "B.Mask" "B.Paste")
			(net "SPI_PCH_CLK")
		)
		(pad "3" smd rect
			(at 0 1.27 180)
			(size 2.159 0.381)
			(layers "B.Cu" "B.Mask" "B.Paste")
			(net "SPI_BMC_CLK")
		)
		(pad "4" smd rect
			(at 0 1.905 180)
			(size 2.159 0.381)
			(layers "B.Cu" "B.Mask" "B.Paste")
			(net "SPI_SWITCH_CLK")
		)
		(pad "5" smd rect
			(at 0 2.54 180)
			(size 2.159 0.381)
			(layers "B.Cu" "B.Mask" "B.Paste")
			(net "SPI_PCH_MOSI")
		)
		(pad "6" smd rect
			(at 0 3.175 180)
			(size 2.159 0.381)
			(layers "B.Cu" "B.Mask" "B.Paste")
			(net "SPI_BMC_DO")
		)
		(pad "7" smd rect
			(at 0 3.81 180)
			(size 2.159 0.381)
			(layers "B.Cu" "B.Mask" "B.Paste")
			(net "SPI_SWITCH_MOSI")
		)
		(pad "8" smd rect
			(at 0 4.445 180)
			(size 2.159 0.381)
			(layers "B.Cu" "B.Mask" "B.Paste")
			(net "GND")
		)
		(pad "9" smd rect
			(at -5.461 4.445 180)
			(size 2.159 0.381)
			(layers "B.Cu" "B.Mask" "B.Paste")
			(net "SPI_SWITCH_CS0_N")
		)
		(pad "10" smd rect
			(at -5.461 3.81 180)
			(size 2.159 0.381)
			(layers "B.Cu" "B.Mask" "B.Paste")
			(net "SPI_BMC_CS0_N")
		)
		(pad "11" smd rect
			(at -5.461 3.175 180)
			(size 2.159 0.381)
			(layers "B.Cu" "B.Mask" "B.Paste")
			(net "SPI_PCH_CS0_N")
		)
		(pad "12" smd rect
			(at -5.461 2.54 180)
			(size 2.159 0.381)
			(layers "B.Cu" "B.Mask" "B.Paste")
			(net "SPI_SWITCH_MISO")
		)
		(pad "13" smd rect
			(at -5.461 1.905 180)
			(size 2.159 0.381)
			(layers "B.Cu" "B.Mask" "B.Paste")
			(net "SPI_BMC_DI")
		)
		(pad "14" smd rect
			(at -5.461 1.27 180)
			(size 2.159 0.381)
			(layers "B.Cu" "B.Mask" "B.Paste")
			(net "SPI_PCH_MISO_R")
		)
		(pad "15" smd rect
			(at -5.461 0.635 180)
			(size 2.159 0.381)
			(layers "B.Cu" "B.Mask" "B.Paste")
			(net "GND")
		)
		(pad "16" smd rect
			(at -5.461 0 180)
			(size 2.159 0.381)
			(layers "B.Cu" "B.Mask" "B.Paste")
			(net "P3V3_STBY")
		)
	)
	(footprint ""
		(layer "B.Cu")
		(at 111.809276 -84.401914)
		(property "Reference" "C8W4"
			(at -1.47828 0.78994 90)
			(unlocked yes)
			(layer "B.SilkS")
			(effects
				(font
					(size 0.4064 0.254)
					(thickness 0.1524)
				)
				(justify mirror)
			)
		)
		(property "Value" ""
			(at 0 0 0)
			(layer "B.Fab")
			(effects
				(font
					(size 1.27 1.27)
				)
				(justify mirror)
			)
		)
		(duplicate_pad_numbers_are_jumpers no)
		(fp_poly
			(pts
				(xy 0.7239 -0.2159) (xy -0.7239 -0.2159) (xy -0.7239 1.9939) (xy 0.7239 1.9939)
			)
			(stroke
				(width 0)
				(type default)
			)
			(fill no)
			(layer "B.CrtYd")
		)
		(fp_line
			(start -0.7239 -0.2159)
			(end 0.7239 -0.2159)
			(stroke
				(width 0.1)
				(type default)
			)
			(layer "B.Fab")
		)
		(fp_line
			(start -0.7239 1.9939)
			(end -0.7239 -0.2159)
			(stroke
				(width 0.1)
				(type default)
			)
			(layer "B.Fab")
		)
		(fp_line
			(start 0.7239 -0.2159)
			(end 0.7239 1.9939)
			(stroke
				(width 0.1)
				(type default)
			)
			(layer "B.Fab")
		)
		(fp_line
			(start 0.7239 1.9939)
			(end -0.7239 1.9939)
			(stroke
				(width 0.1)
				(type default)
			)
			(layer "B.Fab")
		)
		(pad "1" smd rect
			(at 0 0 180)
			(size 1.27 1.016)
			(layers "B.Cu" "B.Mask" "B.Paste")
			(net "PVCCIN_CPU1")
		)
		(pad "2" smd rect
			(at 0 1.778 180)
			(size 1.27 1.016)
			(layers "B.Cu" "B.Mask" "B.Paste")
			(net "GND")
		)
		(zone
			(layer "B.Cu")
			(hatch none 0.5)
			(connect_pads
				(clearance 0)
			)
			(min_thickness 0.25)
			(keepout
				(tracks not_allowed)
				(vias allowed)
				(pads allowed)
				(copperpour not_allowed)
				(footprints allowed)
			)
			(placement
				(enabled no)
				(sheetname "")
			)
			(fill
				(thermal_gap 0.5)
				(thermal_bridge_width 0.5)
				(island_removal_mode 0)
			)
			(polygon
				(pts
					(xy 112.444276 -83.893914) (xy 111.174276 -83.893914) (xy 111.174276 -83.131914) (xy 112.444276 -83.131914)
				)
			)
		)
	)
)
